(kicad_pcb
	(version 20260206)
	(generator "pcbnew")
	(generator_version "10.0")
	(general
		(thickness 1.6)
		(legacy_teardrops no)
	)
	(paper "A4")
	(title_block
		(title "Wiwynn_Tioga_Pass_MB.brd")
		(comment 1 "Tioga Pass / footprints 3493-3498 of 4770")
	)
	(layers
		(0 "F.Cu" signal "TOP")
		(4 "In1.Cu" signal "L2GND")
		(6 "In2.Cu" signal "L3")
		(8 "In3.Cu" signal "L4GND")
		(10 "In4.Cu" signal "L5")
		(12 "In5.Cu" signal "L6GND")
		(14 "In6.Cu" signal "L7VCC")
		(16 "In7.Cu" signal "L8VCC")
		(18 "In8.Cu" signal "L9GND")
		(20 "In9.Cu" signal "L10")
		(22 "In10.Cu" signal "L11GND")
		(24 "In11.Cu" signal "L12")
		(26 "In12.Cu" signal "L13GND")
		(2 "B.Cu" signal "BOTTOM")
		(9 "F.Adhes" user "F.Adhesive")
		(11 "B.Adhes" user "B.Adhesive")
		(13 "F.Paste" user "Package Geometry/Pastemask Top")
		(15 "B.Paste" user "Package Geometry/Pastemask Bottom")
		(5 "F.SilkS" user "Ref Des/Silkscreen Top")
		(7 "B.SilkS" user "Ref Des/Silkscreen Bottom")
		(1 "F.Mask" user "Board Geometry/Soldermask Top")
		(3 "B.Mask" user "Board Geometry/Soldermask Bottom")
		(17 "Dwgs.User" user "User.Drawings")
		(19 "Cmts.User" user "User.Comments")
		(21 "Eco1.User" user "User.Eco1")
		(23 "Eco2.User" user "User.Eco2")
		(25 "Edge.Cuts" user "Board Geometry/Outline")
		(27 "Margin" user)
		(31 "F.CrtYd" user "Package Geometry/Place Bound Top")
		(29 "B.CrtYd" user "Package Geometry/Place Bound Bottom")
		(35 "F.Fab" user "Ref Des/Assembly Top")
		(33 "B.Fab" user "Ref Des/Assembly Bottom")
	)
	(footprint ""
		(layer "B.Cu")
		(at 355.178614 -125.532642 -90)
		(property "Reference" "C3M1"
			(at 0 0 90)
			(layer "B.SilkS")
			(hide yes)
			(effects
				(font
					(size 1.27 1.27)
				)
				(justify mirror)
			)
		)
		(property "Value" ""
			(at 0 0 90)
			(layer "B.Fab")
			(effects
				(font
					(size 1.27 1.27)
				)
				(justify mirror)
			)
		)
		(duplicate_pad_numbers_are_jumpers no)
		(fp_poly
			(pts
				(xy -0.3048 -0.1016) (xy -0.3048 0.9906) (xy 0.3048 0.9906) (xy 0.3048 -0.1016)
			)
			(stroke
				(width 0)
				(type default)
			)
			(fill no)
			(layer "B.CrtYd")
		)
		(fp_line
			(start -0.3048 0.9906)
			(end -0.3048 -0.1016)
			(stroke
				(width 0.1)
				(type default)
			)
			(layer "B.Fab")
		)
		(fp_line
			(start 0.3048 0.9906)
			(end -0.3048 0.9906)
			(stroke
				(width 0.1)
				(type default)
			)
			(layer "B.Fab")
		)
		(fp_line
			(start -0.3048 -0.1016)
			(end 0.3048 -0.1016)
			(stroke
				(width 0.1)
				(type default)
			)
			(layer "B.Fab")
		)
		(fp_line
			(start 0.3048 -0.1016)
			(end 0.3048 0.9906)
			(stroke
				(width 0.1)
				(type default)
			)
			(layer "B.Fab")
		)
		(pad "1" smd rect
			(at 0 0 90)
			(size 0.508 0.508)
			(layers "B.Cu" "B.Mask" "B.Paste")
			(net "P3E_CPU0_PE1_PCH_R_RXN<15>")
		)
		(pad "2" smd rect
			(at 0 0.889 90)
			(size 0.508 0.508)
			(layers "B.Cu" "B.Mask" "B.Paste")
			(net "P3E_CPU0_PE1_PCH_RXN<15>")
		)
		(zone
			(layer "B.Cu")
			(hatch none 0.5)
			(connect_pads
				(clearance 0)
			)
			(min_thickness 0.25)
			(keepout
				(tracks not_allowed)
				(vias allowed)
				(pads allowed)
				(copperpour not_allowed)
				(footprints allowed)
			)
			(placement
				(enabled no)
				(sheetname "")
			)
			(fill
				(thermal_gap 0.5)
				(thermal_bridge_width 0.5)
				(island_removal_mode 0)
			)
			(polygon
				(pts
					(xy 354.543614 -125.278642) (xy 354.543614 -125.786642) (xy 354.924614 -125.786642) (xy 354.924614 -125.278642)
				)
			)
		)
		(zone
			(layer "B.Cu")
			(hatch none 0.5)
			(connect_pads
				(clearance 0)
			)
			(min_thickness 0.25)
			(keepout
				(tracks allowed)
				(vias not_allowed)
				(pads allowed)
				(copperpour not_allowed)
				(footprints allowed)
			)
			(placement
				(enabled no)
				(sheetname "")
			)
			(fill
				(thermal_gap 0.5)
				(thermal_bridge_width 0.5)
				(island_removal_mode 0)
			)
			(polygon
				(pts
					(xy 354.924614 -125.278642) (xy 354.924614 -125.786642) (xy 354.543614 -125.786642) (xy 354.543614 -125.278642)
				)
			)
		)
	)
	(footprint ""
		(layer "B.Cu")
		(at 374.65 -66.04 180)
		(property "Reference" "R2R3"
			(at 0 0 0)
			(layer "B.SilkS")
			(hide yes)
			(effects
				(font
					(size 1.27 1.27)
				)
				(justify mirror)
			)
		)
		(property "Value" ""
			(at 0 0 0)
			(layer "B.Fab")
			(effects
				(font
					(size 1.27 1.27)
				)
				(justify mirror)
			)
		)
		(duplicate_pad_numbers_are_jumpers no)
		(fp_poly
			(pts
				(xy 0.2794 -0.1016) (xy -0.2794 -0.1016) (xy -0.2794 0.9906) (xy 0.2794 0.9906)
			)
			(stroke
				(width 0)
				(type default)
			)
			(fill no)
			(layer "B.CrtYd")
		)
		(fp_line
			(start 0.2794 0.9906)
			(end -0.2794 0.9906)
			(stroke
				(width 0.1)
				(type default)
			)
			(layer "B.Fab")
		)
		(fp_line
			(start 0.2794 -0.1016)
			(end 0.2794 0.9906)
			(stroke
				(width 0.1)
				(type default)
			)
			(layer "B.Fab")
		)
		(fp_line
			(start -0.2794 0.9906)
			(end -0.2794 -0.1016)
			(stroke
				(width 0.1)
				(type default)
			)
			(layer "B.Fab")
		)
		(fp_line
			(start -0.2794 -0.1016)
			(end 0.2794 -0.1016)
			(stroke
				(width 0.1)
				(type default)
			)
			(layer "B.Fab")
		)
		(pad "1" smd rect
			(at 0 0)
			(size 0.508 0.508)
			(layers "B.Cu" "B.Mask" "B.Paste")
			(net "P3V3_STBY")
		)
		(pad "2" smd rect
			(at 0 0.889)
			(size 0.508 0.508)
			(layers "B.Cu" "B.Mask" "B.Paste")
			(net "FM_PLD_DEBUG_MODE_N")
		)
		(zone
			(layer "B.Cu")
			(hatch none 0.5)
			(connect_pads
				(clearance 0)
			)
			(min_thickness 0.25)
			(keepout
				(tracks not_allowed)
				(vias allowed)
				(pads allowed)
				(copperpour not_allowed)
				(footprints allowed)
			)
			(placement
				(enabled no)
				(sheetname "")
			)
			(fill
				(thermal_gap 0.5)
				(thermal_bridge_width 0.5)
				(island_removal_mode 0)
			)
			(polygon
				(pts
					(xy 374.396 -66.675) (xy 374.904 -66.675) (xy 374.904 -66.294) (xy 374.396 -66.294)
				)
			)
		)
		(zone
			(layer "B.Cu")
			(hatch none 0.5)
			(connect_pads
				(clearance 0)
			)
			(min_thickness 0.25)
			(keepout
				(tracks allowed)
				(vias not_allowed)
				(pads allowed)
				(copperpour not_allowed)
				(footprints allowed)
			)
			(placement
				(enabled no)
				(sheetname "")
			)
			(fill
				(thermal_gap 0.5)
				(thermal_bridge_width 0.5)
				(island_removal_mode 0)
			)
			(polygon
				(pts
					(xy 374.396 -66.294) (xy 374.904 -66.294) (xy 374.904 -66.675) (xy 374.396 -66.675)
				)
			)
		)
	)
	(footprint ""
		(layer "B.Cu")
		(at 457.7842 -26.543)
		(property "Reference" "U6W3"
			(at -1.778 -1.46558 0)
			(unlocked yes)
			(layer "B.SilkS")
			(effects
				(font
					(size 0.4064 0.254)
					(thickness 0.1524)
				)
				(justify left mirror)
			)
		)
		(property "Value" ""
			(at 0 0 0)
			(layer "B.Fab")
			(effects
				(font
					(size 1.27 1.27)
				)
				(justify mirror)
			)
		)
		(duplicate_pad_numbers_are_jumpers no)
		(fp_line
			(start -4.191 -0.5969)
			(end -4.191 4.4069)
			(stroke
				(width 0.1524)
				(type default)
			)
			(layer "B.SilkS")
		)
		(fp_line
			(start -4.191 4.4069)
			(end -1.2954 4.4069)
			(stroke
				(width 0.1524)
				(type default)
			)
			(layer "B.SilkS")
		)
		(fp_line
			(start -3.3782 0.6731)
			(end -3.3782 -0.5842)
			(stroke
				(width 0.1524)
				(type default)
			)
			(layer "B.SilkS")
		)
		(fp_line
			(start -2.1082 -0.5842)
			(end -2.1082 0.6731)
			(stroke
				(width 0.1524)
				(type default)
			)
			(layer "B.SilkS")
		)
		(fp_line
			(start -2.1082 0.6731)
			(end -3.3782 0.6731)
			(stroke
				(width 0.1524)
				(type default)
			)
			(layer "B.SilkS")
		)
		(fp_line
			(start -1.2954 -0.5969)
			(end -4.191 -0.5969)
			(stroke
				(width 0.1524)
				(type default)
			)
			(layer "B.SilkS")
		)
		(fp_line
			(start -1.2954 4.4069)
			(end -1.2954 -0.5969)
			(stroke
				(width 0.1524)
				(type default)
			)
			(layer "B.SilkS")
		)
		(fp_circle
			(center 1.382014 -0.7112)
			(end 1.509014 -0.7112)
			(stroke
				(width 0.254)
				(type default)
			)
			(fill no)
			(layer "B.SilkS")
		)
		(fp_poly
			(pts
				(xy -0.7493 -0.5969) (xy -4.7371 -0.5969) (xy -4.7371 4.4069) (xy -0.7493 4.4069)
			)
			(stroke
				(width 0)
				(type default)
			)
			(fill no)
			(layer "B.CrtYd")
		)
		(fp_line
			(start -4.7371 -0.5969)
			(end -4.7371 4.4069)
			(stroke
				(width 0.1)
				(type default)
			)
			(layer "B.Fab")
		)
		(fp_line
			(start -4.7371 4.4069)
			(end -0.7493 4.4069)
			(stroke
				(width 0.1)
				(type default)
			)
			(layer "B.Fab")
		)
		(fp_line
			(start -3.3782 0.6731)
			(end -3.3782 -0.5842)
			(stroke
				(width 0.1)
				(type default)
			)
			(layer "B.Fab")
		)
		(fp_line
			(start -2.1082 -0.5842)
			(end -2.1082 0.6731)
			(stroke
				(width 0.1)
				(type default)
			)
			(layer "B.Fab")
		)
		(fp_line
			(start -2.1082 0.6731)
			(end -3.3782 0.6731)
			(stroke
				(width 0.1)
				(type default)
			)
			(layer "B.Fab")
		)
		(fp_line
			(start -0.7493 -0.5969)
			(end -4.7371 -0.5969)
			(stroke
				(width 0.1)
				(type default)
			)
			(layer "B.Fab")
		)
		(fp_line
			(start -0.7493 4.4069)
			(end -0.7493 -0.5969)
			(stroke
				(width 0.1)
				(type default)
			)
			(layer "B.Fab")
		)
		(fp_circle
			(center 1.382014 -0.7112)
			(end 1.509014 -0.7112)
			(stroke
				(width 0.254)
				(type default)
			)
			(fill no)
			(layer "B.Fab")
		)
		(pad "1" smd rect
			(at 0 0 180)
			(size 1.9304 0.635)
			(layers "B.Cu" "B.Mask" "B.Paste")
			(net "PU_ID_EEPROM_A0")
		)
		(pad "2" smd rect
			(at 0 1.27 180)
			(size 1.9304 0.635)
			(layers "B.Cu" "B.Mask" "B.Paste")
			(net "GND")
		)
		(pad "3" smd rect
			(at 0 2.54 180)
			(size 1.9304 0.635)
			(layers "B.Cu" "B.Mask" "B.Paste")
			(net "GND")
		)
		(pad "4" smd rect
			(at 0 3.81 180)
			(size 1.9304 0.635)
			(layers "B.Cu" "B.Mask" "B.Paste")
			(net "GND")
		)
		(pad "5" smd rect
			(at -5.4864 3.81 180)
			(size 1.9304 0.635)
			(layers "B.Cu" "B.Mask" "B.Paste")
			(net "SMB_HOST_STBY_LVC3_SDA_R3")
		)
		(pad "6" smd rect
			(at -5.4864 2.54 180)
			(size 1.9304 0.635)
			(layers "B.Cu" "B.Mask" "B.Paste")
			(net "SMB_HOST_STBY_LVC3_SCL_R3")
		)
		(pad "7" smd rect
			(at -5.4864 1.27 180)
			(size 1.9304 0.635)
			(layers "B.Cu" "B.Mask" "B.Paste")
			(net "PD_ID_EEPROM_WP")
		)
		(pad "8" smd rect
			(at -5.4864 0 180)
			(size 1.9304 0.635)
			(layers "B.Cu" "B.Mask" "B.Paste")
			(net "P3V3_STBY")
		)
	)
	(footprint ""
		(layer "B.Cu")
		(at 355.178614 -126.624842 -90)
		(property "Reference" "C3M2"
			(at 0 0 90)
			(layer "B.SilkS")
			(hide yes)
			(effects
				(font
					(size 1.27 1.27)
				)
				(justify mirror)
			)
		)
		(property "Value" ""
			(at 0 0 90)
			(layer "B.Fab")
			(effects
				(font
					(size 1.27 1.27)
				)
				(justify mirror)
			)
		)
		(duplicate_pad_numbers_are_jumpers no)
		(fp_poly
			(pts
				(xy -0.3048 -0.1016) (xy -0.3048 0.9906) (xy 0.3048 0.9906) (xy 0.3048 -0.1016)
			)
			(stroke
				(width 0)
				(type default)
			)
			(fill no)
			(layer "B.CrtYd")
		)
		(fp_line
			(start -0.3048 0.9906)
			(end -0.3048 -0.1016)
			(stroke
				(width 0.1)
				(type default)
			)
			(layer "B.Fab")
		)
		(fp_line
			(start 0.3048 0.9906)
			(end -0.3048 0.9906)
			(stroke
				(width 0.1)
				(type default)
			)
			(layer "B.Fab")
		)
		(fp_line
			(start -0.3048 -0.1016)
			(end 0.3048 -0.1016)
			(stroke
				(width 0.1)
				(type default)
			)
			(layer "B.Fab")
		)
		(fp_line
			(start 0.3048 -0.1016)
			(end 0.3048 0.9906)
			(stroke
				(width 0.1)
				(type default)
			)
			(layer "B.Fab")
		)
		(pad "1" smd rect
			(at 0 0 90)
			(size 0.508 0.508)
			(layers "B.Cu" "B.Mask" "B.Paste")
			(net "P3E_CPU0_PE1_PCH_R_RXP<15>")
		)
		(pad "2" smd rect
			(at 0 0.889 90)
			(size 0.508 0.508)
			(layers "B.Cu" "B.Mask" "B.Paste")
			(net "P3E_CPU0_PE1_PCH_RXP<15>")
		)
		(zone
			(layer "B.Cu")
			(hatch none 0.5)
			(connect_pads
				(clearance 0)
			)
			(min_thickness 0.25)
			(keepout
				(tracks not_allowed)
				(vias allowed)
				(pads allowed)
				(copperpour not_allowed)
				(footprints allowed)
			)
			(placement
				(enabled no)
				(sheetname "")
			)
			(fill
				(thermal_gap 0.5)
				(thermal_bridge_width 0.5)
				(island_removal_mode 0)
			)
			(polygon
				(pts
					(xy 354.543614 -126.370842) (xy 354.543614 -126.878842) (xy 354.924614 -126.878842) (xy 354.924614 -126.370842)
				)
			)
		)
		(zone
			(layer "B.Cu")
			(hatch none 0.5)
			(connect_pads
				(clearance 0)
			)
			(min_thickness 0.25)
			(keepout
				(tracks allowed)
				(vias not_allowed)
				(pads allowed)
				(copperpour not_allowed)
				(footprints allowed)
			)
			(placement
				(enabled no)
				(sheetname "")
			)
			(fill
				(thermal_gap 0.5)
				(thermal_bridge_width 0.5)
				(island_removal_mode 0)
			)
			(polygon
				(pts
					(xy 354.924614 -126.370842) (xy 354.924614 -126.878842) (xy 354.543614 -126.878842) (xy 354.543614 -126.370842)
				)
			)
		)
	)
	(footprint ""
		(layer "B.Cu")
		(at 195.453 -17.723612 90)
		(property "Reference" "C6T1"
			(at 0 0 90)
			(layer "B.SilkS")
			(hide yes)
			(effects
				(font
					(size 1.27 1.27)
				)
				(justify mirror)
			)
		)
		(property "Value" ""
			(at 0 0 90)
			(layer "B.Fab")
			(effects
				(font
					(size 1.27 1.27)
				)
				(justify mirror)
			)
		)
		(duplicate_pad_numbers_are_jumpers no)
		(fp_poly
			(pts
				(xy -0.3048 -0.1016) (xy -0.3048 0.9906) (xy 0.3048 0.9906) (xy 0.3048 -0.1016)
			)
			(stroke
				(width 0)
				(type default)
			)
			(fill no)
			(layer "B.CrtYd")
		)
		(fp_line
			(start 0.3048 -0.1016)
			(end 0.3048 0.9906)
			(stroke
				(width 0.1)
				(type default)
			)
			(layer "B.Fab")
		)
		(fp_line
			(start -0.3048 -0.1016)
			(end 0.3048 -0.1016)
			(stroke
				(width 0.1)
				(type default)
			)
			(layer "B.Fab")
		)
		(fp_line
			(start 0.3048 0.9906)
			(end -0.3048 0.9906)
			(stroke
				(width 0.1)
				(type default)
			)
			(layer "B.Fab")
		)
		(fp_line
			(start -0.3048 0.9906)
			(end -0.3048 -0.1016)
			(stroke
				(width 0.1)
				(type default)
			)
			(layer "B.Fab")
		)
		(pad "1" smd rect
			(at 0 0 270)
			(size 0.508 0.508)
			(layers "B.Cu" "B.Mask" "B.Paste")
			(net "M_A_VREF")
		)
		(pad "2" smd rect
			(at 0 0.889 270)
			(size 0.508 0.508)
			(layers "B.Cu" "B.Mask" "B.Paste")
			(net "GND")
		)
		(zone
			(layer "B.Cu")
			(hatch none 0.5)
			(connect_pads
				(clearance 0)
			)
			(min_thickness 0.25)
			(keepout
				(tracks allowed)
				(vias not_allowed)
				(pads allowed)
				(copperpour not_allowed)
				(footprints allowed)
			)
			(placement
				(enabled no)
				(sheetname "")
			)
			(fill
				(thermal_gap 0.5)
				(thermal_bridge_width 0.5)
				(island_removal_mode 0)
			)
			(polygon
				(pts
					(xy 195.707 -17.977612) (xy 195.707 -17.469612) (xy 196.088 -17.469612) (xy 196.088 -17.977612)
				)
			)
		)
		(zone
			(layer "B.Cu")
			(hatch none 0.5)
			(connect_pads
				(clearance 0)
			)
			(min_thickness 0.25)
			(keepout
				(tracks not_allowed)
				(vias allowed)
				(pads allowed)
				(copperpour not_allowed)
				(footprints allowed)
			)
			(placement
				(enabled no)
				(sheetname "")
			)
			(fill
				(thermal_gap 0.5)
				(thermal_bridge_width 0.5)
				(island_removal_mode 0)
			)
			(polygon
				(pts
					(xy 196.088 -17.977612) (xy 196.088 -17.469612) (xy 195.707 -17.469612) (xy 195.707 -17.977612)
				)
			)
		)
	)
	(footprint ""
		(layer "B.Cu")
		(at 418.8206 -11.587734 180)
		(property "Reference" "Q2T1"
			(at 1.22047 3.2004 90)
			(unlocked yes)
			(layer "B.SilkS")
			(effects
				(font
					(size 0.7874 0.5842)
					(thickness 0.1524)
				)
				(justify left mirror)
			)
		)
		(property "Value" ""
			(at 0 0 0)
			(layer "B.Fab")
			(effects
				(font
					(size 1.27 1.27)
				)
				(justify mirror)
			)
		)
		(duplicate_pad_numbers_are_jumpers no)
		(fp_line
			(start -0.381 0.635)
			(end -0.381 1.27)
			(stroke
				(width 0.1524)
				(type default)
			)
			(layer "B.SilkS")
		)
		(fp_line
			(start -0.9525 2.4765)
			(end -1.778 2.4765)
			(stroke
				(width 0.1524)
				(type default)
			)
			(layer "B.SilkS")
		)
		(fp_line
			(start -0.9525 -0.5715)
			(end -1.778 -0.5715)
			(stroke
				(width 0.1524)
				(type default)
			)
			(layer "B.SilkS")
		)
		(fp_line
			(start -1.778 2.4765)
			(end -1.778 1.5875)
			(stroke
				(width 0.1524)
				(type default)
			)
			(layer "B.SilkS")
		)
		(fp_line
			(start -1.778 -0.5715)
			(end -1.778 0.3175)
			(stroke
				(width 0.1524)
				(type default)
			)
			(layer "B.SilkS")
		)
		(fp_circle
			(center 0.9525 -0.9271)
			(end 0.8255 -0.9271)
			(stroke
				(width 0.254)
				(type default)
			)
			(fill no)
			(layer "B.SilkS")
		)
		(fp_poly
			(pts
				(xy -1.778 2.4765) (xy -0.381 2.4765) (xy -0.381 -0.5715) (xy -1.778 -0.5715)
			)
			(stroke
				(width 0)
				(type default)
			)
			(fill no)
			(layer "B.CrtYd")
		)
		(fp_line
			(start -0.381 2.4765)
			(end -1.778 2.4765)
			(stroke
				(width 0.1)
				(type default)
			)
			(layer "B.Fab")
		)
		(fp_line
			(start -0.381 -0.5715)
			(end -0.381 2.4765)
			(stroke
				(width 0.1)
				(type default)
			)
			(layer "B.Fab")
		)
		(fp_line
			(start -1.778 2.4765)
			(end -1.778 -0.5715)
			(stroke
				(width 0.1)
				(type default)
			)
			(layer "B.Fab")
		)
		(fp_line
			(start -1.778 -0.5715)
			(end -0.381 -0.5715)
			(stroke
				(width 0.1)
				(type default)
			)
			(layer "B.Fab")
		)
		(fp_circle
			(center 0.9525 -0.9271)
			(end 0.8255 -0.9271)
			(stroke
				(width 0.254)
				(type default)
			)
			(fill no)
			(layer "B.Fab")
		)
		(pad "1" smd rect
			(at 0 0)
			(size 1.143 0.508)
			(layers "B.Cu" "B.Mask" "B.Paste")
			(net "H_CPU0_FAST_WAKE_B_N")
		)
		(pad "2" smd rect
			(at 0 1.905)
			(size 1.143 0.508)
			(layers "B.Cu" "B.Mask" "B.Paste")
			(net "GND")
		)
		(pad "3" smd rect
			(at -2.159 0.9525)
			(size 1.143 0.508)
			(layers "B.Cu" "B.Mask" "B.Paste")
			(net "H_CPU0_FAST_WAKE")
		)
	)
)
